(kicad_pcb
	(version 20260206)
	(generator "pcbnew")
	(generator_version "10.0")
	(general
		(thickness 1.6)
		(legacy_teardrops no)
	)
	(paper "A4")
	(title_block
		(title "01162023_DA0F0TEBIF0_F0T_Expander_BD_F_brd_V02_OCP.brd")
		(comment 1 "Grand Teton / footprints 1181-1187 of 9728")
	)
	(layers
		(0 "F.Cu" signal "TOP")
		(4 "In1.Cu" signal "GND")
		(6 "In2.Cu" signal "VCC")
		(8 "In3.Cu" signal "VCC1")
		(10 "In4.Cu" signal "GND1")
		(12 "In5.Cu" signal "IN1")
		(14 "In6.Cu" signal "GND2")
		(16 "In7.Cu" signal "IN2")
		(18 "In8.Cu" signal "GND3")
		(20 "In9.Cu" signal "IN3")
		(22 "In10.Cu" signal "GND4")
		(24 "In11.Cu" signal "IN4")
		(26 "In12.Cu" signal "GND5")
		(28 "In13.Cu" signal "IN5")
		(30 "In14.Cu" signal "GND6")
		(32 "In15.Cu" signal "IN6")
		(34 "In16.Cu" signal "GND7")
		(2 "B.Cu" signal "BOTTOM")
		(9 "F.Adhes" user "F.Adhesive")
		(11 "B.Adhes" user "B.Adhesive")
		(13 "F.Paste" user "Package Geometry/Pastemask Top")
		(15 "B.Paste" user "Package Geometry/Pastemask Bottom")
		(5 "F.SilkS" user "Ref Des/Silkscreen Top")
		(7 "B.SilkS" user "Ref Des/Silkscreen Bottom")
		(1 "F.Mask" user "Board Geometry/Soldermask Top")
		(3 "B.Mask" user "Board Geometry/Soldermask Bottom")
		(17 "Dwgs.User" user "User.Drawings")
		(19 "Cmts.User" user "User.Comments")
		(21 "Eco1.User" user "User.Eco1")
		(23 "Eco2.User" user "User.Eco2")
		(25 "Edge.Cuts" user "Board Geometry/Outline")
		(27 "Margin" user)
		(31 "F.CrtYd" user "Package Geometry/Place Bound Top")
		(29 "B.CrtYd" user "Package Geometry/Place Bound Bottom")
		(35 "F.Fab" user "Ref Des/Assembly Top")
		(33 "B.Fab" user "Ref Des/Assembly Bottom")
	)
	(footprint ""
		(layer "F.Cu")
		(at 249.822716 -22.867366 90)
		(property "Reference" "C3931"
			(at 0 0 90)
			(layer "F.SilkS")
			(hide yes)
			(effects
				(font
					(size 1.27 1.27)
				)
			)
		)
		(property "Value" ""
			(at 0 0 90)
			(layer "F.Fab")
			(effects
				(font
					(size 1.27 1.27)
				)
			)
		)
		(duplicate_pad_numbers_are_jumpers no)
		(fp_line
			(start 0.7874 -0.4064)
			(end 0.7874 0.4064)
			(stroke
				(width 0.1524)
				(type default)
			)
			(layer "F.SilkS")
		)
		(fp_line
			(start -0.7874 -0.4064)
			(end 0.7874 -0.4064)
			(stroke
				(width 0.1524)
				(type default)
			)
			(layer "F.SilkS")
		)
		(fp_line
			(start 0.7874 0.4064)
			(end -0.7874 0.4064)
			(stroke
				(width 0.1524)
				(type default)
			)
			(layer "F.SilkS")
		)
		(fp_line
			(start -0.7874 0.4064)
			(end -0.7874 -0.4064)
			(stroke
				(width 0.1524)
				(type default)
			)
			(layer "F.SilkS")
		)
		(fp_line
			(start -0.12065 -0.305054)
			(end -0.12065 -0.2794)
			(stroke
				(width 0.1)
				(type default)
			)
			(layer "F.Fab")
		)
		(fp_line
			(start -0.67945 -0.305054)
			(end -0.12065 -0.305054)
			(stroke
				(width 0.1)
				(type default)
			)
			(layer "F.Fab")
		)
		(fp_line
			(start 0.67945 -0.3048)
			(end 0.67945 0.3048)
			(stroke
				(width 0.1)
				(type default)
			)
			(layer "F.Fab")
		)
		(fp_line
			(start 0.12065 -0.3048)
			(end 0.67945 -0.3048)
			(stroke
				(width 0.1)
				(type default)
			)
			(layer "F.Fab")
		)
		(fp_line
			(start 0.12065 -0.2794)
			(end 0.12065 -0.3048)
			(stroke
				(width 0.1)
				(type default)
			)
			(layer "F.Fab")
		)
		(fp_line
			(start -0.12065 -0.2794)
			(end 0.12065 -0.2794)
			(stroke
				(width 0.1)
				(type default)
			)
			(layer "F.Fab")
		)
		(fp_line
			(start 0.120396 0.2794)
			(end -0.12065 0.2794)
			(stroke
				(width 0.1)
				(type default)
			)
			(layer "F.Fab")
		)
		(fp_line
			(start -0.12065 0.2794)
			(end -0.12065 0.3048)
			(stroke
				(width 0.1)
				(type default)
			)
			(layer "F.Fab")
		)
		(fp_line
			(start 0.67945 0.3048)
			(end 0.120396 0.3048)
			(stroke
				(width 0.1)
				(type default)
			)
			(layer "F.Fab")
		)
		(fp_line
			(start 0.120396 0.3048)
			(end 0.120396 0.2794)
			(stroke
				(width 0.1)
				(type default)
			)
			(layer "F.Fab")
		)
		(fp_line
			(start -0.12065 0.3048)
			(end -0.67945 0.3048)
			(stroke
				(width 0.1)
				(type default)
			)
			(layer "F.Fab")
		)
		(fp_line
			(start -0.67945 0.3048)
			(end -0.67945 -0.305054)
			(stroke
				(width 0.1)
				(type default)
			)
			(layer "F.Fab")
		)
		(pad "1" smd circle
			(at -0.40005 0 90)
			(size 0 0)
			(layers "F.Cu" "F.Mask" "F.Paste")
			(net "P12V_SSD8")
		)
		(pad "2" smd circle
			(at 0.40005 0 90)
			(size 0 0)
			(layers "F.Cu" "F.Mask" "F.Paste")
			(net "GND")
		)
	)
	(footprint ""
		(layer "F.Cu")
		(at 353.147884 -40.037258 90)
		(property "Reference" "U372"
			(at 0.196342 2.402586 90)
			(unlocked yes)
			(layer "F.SilkS")
			(effects
				(font
					(size 0.7874 0.5842)
					(thickness 0.1524)
				)
			)
		)
		(property "Value" ""
			(at 0 0 90)
			(layer "F.Fab")
			(effects
				(font
					(size 1.27 1.27)
				)
			)
		)
		(duplicate_pad_numbers_are_jumpers no)
		(fp_line
			(start -1.949958 -1.610106)
			(end 1.949958 -1.610106)
			(stroke
				(width 0.1524)
				(type default)
			)
			(layer "F.SilkS")
		)
		(fp_line
			(start 1.949958 -1.560068)
			(end 1.949958 1.610106)
			(stroke
				(width 0.1524)
				(type default)
			)
			(layer "F.SilkS")
		)
		(fp_line
			(start 1.949958 1.610106)
			(end -1.949958 1.610106)
			(stroke
				(width 0.1524)
				(type default)
			)
			(layer "F.SilkS")
		)
		(fp_line
			(start -1.949958 1.610106)
			(end -1.949958 -1.610106)
			(stroke
				(width 0.1524)
				(type default)
			)
			(layer "F.SilkS")
		)
		(fp_line
			(start 0.750062 -1.560068)
			(end 0.750062 1.560068)
			(stroke
				(width 0.1)
				(type default)
			)
			(layer "F.Fab")
		)
		(fp_line
			(start -0.750062 -1.560068)
			(end 0.750062 -1.560068)
			(stroke
				(width 0.1)
				(type default)
			)
			(layer "F.Fab")
		)
		(fp_line
			(start 0.750062 1.560068)
			(end -0.750062 1.560068)
			(stroke
				(width 0.1)
				(type default)
			)
			(layer "F.Fab")
		)
		(fp_line
			(start -0.750062 1.560068)
			(end -0.750062 -1.560068)
			(stroke
				(width 0.1)
				(type default)
			)
			(layer "F.Fab")
		)
		(pad "D" smd rect
			(at 1.100074 0)
			(size 1.016 1.4224)
			(layers "F.Cu" "F.Mask" "F.Paste")
			(net "SSD12_AUX_P3V3_EN")
		)
		(pad "G" smd rect
			(at -1.100074 -0.94996)
			(size 1.016 1.4224)
			(layers "F.Cu" "F.Mask" "F.Paste")
			(net "PRSNT_SSD12_R1_N")
		)
		(pad "S" smd rect
			(at -1.100074 0.94996)
			(size 1.016 1.4224)
			(layers "F.Cu" "F.Mask" "F.Paste")
			(net "GND")
		)
	)
	(footprint ""
		(layer "F.Cu")
		(at 336.467704 -52.035456 180)
		(property "Reference" "R876"
			(at 0 0 180)
			(layer "F.SilkS")
			(hide yes)
			(effects
				(font
					(size 1.27 1.27)
				)
			)
		)
		(property "Value" ""
			(at 0 0 180)
			(layer "F.Fab")
			(effects
				(font
					(size 1.27 1.27)
				)
			)
		)
		(duplicate_pad_numbers_are_jumpers no)
		(fp_line
			(start 0.7874 0.4064)
			(end -0.7874 0.4064)
			(stroke
				(width 0.1524)
				(type default)
			)
			(layer "F.SilkS")
		)
		(fp_line
			(start 0.7874 -0.4064)
			(end 0.7874 0.4064)
			(stroke
				(width 0.1524)
				(type default)
			)
			(layer "F.SilkS")
		)
		(fp_line
			(start -0.7874 0.4064)
			(end -0.7874 -0.4064)
			(stroke
				(width 0.1524)
				(type default)
			)
			(layer "F.SilkS")
		)
		(fp_line
			(start -0.7874 -0.4064)
			(end 0.7874 -0.4064)
			(stroke
				(width 0.1524)
				(type default)
			)
			(layer "F.SilkS")
		)
		(fp_line
			(start 0.67945 0.3048)
			(end 0.120396 0.3048)
			(stroke
				(width 0.1)
				(type default)
			)
			(layer "F.Fab")
		)
		(fp_line
			(start 0.67945 -0.3048)
			(end 0.67945 0.3048)
			(stroke
				(width 0.1)
				(type default)
			)
			(layer "F.Fab")
		)
		(fp_line
			(start 0.12065 -0.2794)
			(end 0.12065 -0.3048)
			(stroke
				(width 0.1)
				(type default)
			)
			(layer "F.Fab")
		)
		(fp_line
			(start 0.12065 -0.3048)
			(end 0.67945 -0.3048)
			(stroke
				(width 0.1)
				(type default)
			)
			(layer "F.Fab")
		)
		(fp_line
			(start 0.120396 0.3048)
			(end 0.120396 0.2794)
			(stroke
				(width 0.1)
				(type default)
			)
			(layer "F.Fab")
		)
		(fp_line
			(start 0.120396 0.2794)
			(end -0.12065 0.2794)
			(stroke
				(width 0.1)
				(type default)
			)
			(layer "F.Fab")
		)
		(fp_line
			(start -0.12065 0.3048)
			(end -0.67945 0.3048)
			(stroke
				(width 0.1)
				(type default)
			)
			(layer "F.Fab")
		)
		(fp_line
			(start -0.12065 0.2794)
			(end -0.12065 0.3048)
			(stroke
				(width 0.1)
				(type default)
			)
			(layer "F.Fab")
		)
		(fp_line
			(start -0.12065 -0.2794)
			(end 0.12065 -0.2794)
			(stroke
				(width 0.1)
				(type default)
			)
			(layer "F.Fab")
		)
		(fp_line
			(start -0.12065 -0.305054)
			(end -0.12065 -0.2794)
			(stroke
				(width 0.1)
				(type default)
			)
			(layer "F.Fab")
		)
		(fp_line
			(start -0.67945 0.3048)
			(end -0.67945 -0.305054)
			(stroke
				(width 0.1)
				(type default)
			)
			(layer "F.Fab")
		)
		(fp_line
			(start -0.67945 -0.305054)
			(end -0.12065 -0.305054)
			(stroke
				(width 0.1)
				(type default)
			)
			(layer "F.Fab")
		)
		(pad "1" smd circle
			(at -0.40005 0 180)
			(size 0 0)
			(layers "F.Cu" "F.Mask" "F.Paste")
			(net "P3V3_AUX")
		)
		(pad "2" smd circle
			(at 0.40005 0 180)
			(size 0 0)
			(layers "F.Cu" "F.Mask" "F.Paste")
			(net "PWRGD_P12V_SSD11")
		)
	)
	(footprint ""
		(layer "F.Cu")
		(at 403.657816 -27.006296 -90)
		(property "Reference" "PR7127"
			(at 0 0 270)
			(layer "F.SilkS")
			(hide yes)
			(effects
				(font
					(size 1.27 1.27)
				)
			)
		)
		(property "Value" ""
			(at 0 0 270)
			(layer "F.Fab")
			(effects
				(font
					(size 1.27 1.27)
				)
			)
		)
		(duplicate_pad_numbers_are_jumpers no)
		(fp_line
			(start -0.7874 0.4064)
			(end -0.7874 -0.4064)
			(stroke
				(width 0.1524)
				(type default)
			)
			(layer "F.SilkS")
		)
		(fp_line
			(start 0.7874 0.4064)
			(end -0.7874 0.4064)
			(stroke
				(width 0.1524)
				(type default)
			)
			(layer "F.SilkS")
		)
		(fp_line
			(start -0.7874 -0.4064)
			(end 0.7874 -0.4064)
			(stroke
				(width 0.1524)
				(type default)
			)
			(layer "F.SilkS")
		)
		(fp_line
			(start 0.7874 -0.4064)
			(end 0.7874 0.4064)
			(stroke
				(width 0.1524)
				(type default)
			)
			(layer "F.SilkS")
		)
		(fp_line
			(start -0.67945 0.3048)
			(end -0.67945 -0.305054)
			(stroke
				(width 0.1)
				(type default)
			)
			(layer "F.Fab")
		)
		(fp_line
			(start -0.12065 0.3048)
			(end -0.67945 0.3048)
			(stroke
				(width 0.1)
				(type default)
			)
			(layer "F.Fab")
		)
		(fp_line
			(start 0.120396 0.3048)
			(end 0.120396 0.2794)
			(stroke
				(width 0.1)
				(type default)
			)
			(layer "F.Fab")
		)
		(fp_line
			(start 0.67945 0.3048)
			(end 0.120396 0.3048)
			(stroke
				(width 0.1)
				(type default)
			)
			(layer "F.Fab")
		)
		(fp_line
			(start -0.12065 0.2794)
			(end -0.12065 0.3048)
			(stroke
				(width 0.1)
				(type default)
			)
			(layer "F.Fab")
		)
		(fp_line
			(start 0.120396 0.2794)
			(end -0.12065 0.2794)
			(stroke
				(width 0.1)
				(type default)
			)
			(layer "F.Fab")
		)
		(fp_line
			(start -0.12065 -0.2794)
			(end 0.12065 -0.2794)
			(stroke
				(width 0.1)
				(type default)
			)
			(layer "F.Fab")
		)
		(fp_line
			(start 0.12065 -0.2794)
			(end 0.12065 -0.3048)
			(stroke
				(width 0.1)
				(type default)
			)
			(layer "F.Fab")
		)
		(fp_line
			(start 0.12065 -0.3048)
			(end 0.67945 -0.3048)
			(stroke
				(width 0.1)
				(type default)
			)
			(layer "F.Fab")
		)
		(fp_line
			(start 0.67945 -0.3048)
			(end 0.67945 0.3048)
			(stroke
				(width 0.1)
				(type default)
			)
			(layer "F.Fab")
		)
		(fp_line
			(start -0.67945 -0.305054)
			(end -0.12065 -0.305054)
			(stroke
				(width 0.1)
				(type default)
			)
			(layer "F.Fab")
		)
		(fp_line
			(start -0.12065 -0.305054)
			(end -0.12065 -0.2794)
			(stroke
				(width 0.1)
				(type default)
			)
			(layer "F.Fab")
		)
		(pad "1" smd circle
			(at -0.40005 0 270)
			(size 0 0)
			(layers "F.Cu" "F.Mask" "F.Paste")
			(net "P3V3_SSD14_CO_MODE")
		)
		(pad "2" smd circle
			(at 0.40005 0 270)
			(size 0 0)
			(layers "F.Cu" "F.Mask" "F.Paste")
			(net "GND")
		)
	)
	(footprint ""
		(layer "F.Cu")
		(at 331.778102 -89.269316 180)
		(property "Reference" "C2681"
			(at 0 0 180)
			(layer "F.SilkS")
			(hide yes)
			(effects
				(font
					(size 1.27 1.27)
				)
			)
		)
		(property "Value" ""
			(at 0 0 180)
			(layer "F.Fab")
			(effects
				(font
					(size 1.27 1.27)
				)
			)
		)
		(duplicate_pad_numbers_are_jumpers no)
		(fp_line
			(start 1.2954 0.5842)
			(end -1.2954 0.5842)
			(stroke
				(width 0.1524)
				(type default)
			)
			(layer "F.SilkS")
		)
		(fp_line
			(start 1.2954 -0.5842)
			(end 1.2954 0.5842)
			(stroke
				(width 0.1524)
				(type default)
			)
			(layer "F.SilkS")
		)
		(fp_line
			(start -1.2954 0.5842)
			(end -1.2954 -0.5842)
			(stroke
				(width 0.1524)
				(type default)
			)
			(layer "F.SilkS")
		)
		(fp_line
			(start -1.2954 -0.5842)
			(end 1.2954 -0.5842)
			(stroke
				(width 0.1524)
				(type default)
			)
			(layer "F.SilkS")
		)
		(fp_line
			(start 1.1938 0.4064)
			(end 0.8636 0.4064)
			(stroke
				(width 0.1)
				(type default)
			)
			(layer "F.Fab")
		)
		(fp_line
			(start 1.1938 -0.4064)
			(end 1.1938 0.4064)
			(stroke
				(width 0.1)
				(type default)
			)
			(layer "F.Fab")
		)
		(fp_line
			(start 0.8636 0.4572)
			(end -0.8636 0.4572)
			(stroke
				(width 0.1)
				(type default)
			)
			(layer "F.Fab")
		)
		(fp_line
			(start 0.8636 0.4064)
			(end 0.8636 0.4572)
			(stroke
				(width 0.1)
				(type default)
			)
			(layer "F.Fab")
		)
		(fp_line
			(start 0.8636 -0.4064)
			(end 1.1938 -0.4064)
			(stroke
				(width 0.1)
				(type default)
			)
			(layer "F.Fab")
		)
		(fp_line
			(start 0.8636 -0.4572)
			(end 0.8636 -0.4064)
			(stroke
				(width 0.1)
				(type default)
			)
			(layer "F.Fab")
		)
		(fp_line
			(start -0.8636 0.4572)
			(end -0.8636 0.4064)
			(stroke
				(width 0.1)
				(type default)
			)
			(layer "F.Fab")
		)
		(fp_line
			(start -0.8636 0.4064)
			(end -1.1938 0.4064)
			(stroke
				(width 0.1)
				(type default)
			)
			(layer "F.Fab")
		)
		(fp_line
			(start -0.8636 -0.4064)
			(end -0.8636 -0.4572)
			(stroke
				(width 0.1)
				(type default)
			)
			(layer "F.Fab")
		)
		(fp_line
			(start -0.8636 -0.4572)
			(end 0.8636 -0.4572)
			(stroke
				(width 0.1)
				(type default)
			)
			(layer "F.Fab")
		)
		(fp_line
			(start -1.1938 0.4064)
			(end -1.1938 -0.4064)
			(stroke
				(width 0.1)
				(type default)
			)
			(layer "F.Fab")
		)
		(fp_line
			(start -1.1938 -0.4064)
			(end -0.8636 -0.4064)
			(stroke
				(width 0.1)
				(type default)
			)
			(layer "F.Fab")
		)
		(pad "1" smd rect
			(at -0.7366 0 90)
			(size 0.7112 0.8128)
			(layers "F.Cu" "F.Mask" "F.Paste")
			(net "P3V3_VDDAR_9ZXL0851_8_15")
		)
		(pad "2" smd rect
			(at 0.7366 0 90)
			(size 0.7112 0.8128)
			(layers "F.Cu" "F.Mask" "F.Paste")
			(net "GND")
		)
	)
	(footprint ""
		(layer "F.Cu")
		(at 283.416502 -343.952322 90)
		(property "Reference" "C599"
			(at 0 0 90)
			(layer "F.SilkS")
			(hide yes)
			(effects
				(font
					(size 1.27 1.27)
				)
			)
		)
		(property "Value" ""
			(at 0 0 90)
			(layer "F.Fab")
			(effects
				(font
					(size 1.27 1.27)
				)
			)
		)
		(duplicate_pad_numbers_are_jumpers no)
		(fp_line
			(start 0.299974 -0.150114)
			(end 0.299974 0.150114)
			(stroke
				(width 0.1)
				(type default)
			)
			(layer "F.Fab")
		)
		(fp_line
			(start -0.299974 -0.150114)
			(end 0.299974 -0.150114)
			(stroke
				(width 0.1)
				(type default)
			)
			(layer "F.Fab")
		)
		(fp_line
			(start 0.299974 0.150114)
			(end -0.299974 0.150114)
			(stroke
				(width 0.1)
				(type default)
			)
			(layer "F.Fab")
		)
		(fp_line
			(start -0.299974 0.150114)
			(end -0.299974 -0.150114)
			(stroke
				(width 0.1)
				(type default)
			)
			(layer "F.Fab")
		)
		(pad "1" smd rect
			(at -0.2667 0 90)
			(size 0.3048 0.381)
			(layers "F.Cu" "F.Mask" "F.Paste")
			(net "P5E_PEX2_STN7_TX_DP<119>")
		)
		(pad "2" smd rect
			(at 0.2667 0 90)
			(size 0.3048 0.381)
			(layers "F.Cu" "F.Mask" "F.Paste")
			(net "P5E_PEX2_STN7_TX_C_DP<119>")
		)
	)
	(footprint ""
		(layer "F.Cu")
		(at 180.8099 -198.997062 180)
		(property "Reference" "C2095"
			(at 0 0 180)
			(layer "F.SilkS")
			(hide yes)
			(effects
				(font
					(size 1.27 1.27)
				)
			)
		)
		(property "Value" ""
			(at 0 0 180)
			(layer "F.Fab")
			(effects
				(font
					(size 1.27 1.27)
				)
			)
		)
		(duplicate_pad_numbers_are_jumpers no)
		(fp_line
			(start 0.7874 0.4064)
			(end -0.7874 0.4064)
			(stroke
				(width 0.1524)
				(type default)
			)
			(layer "F.SilkS")
		)
		(fp_line
			(start 0.7874 -0.4064)
			(end 0.7874 0.4064)
			(stroke
				(width 0.1524)
				(type default)
			)
			(layer "F.SilkS")
		)
		(fp_line
			(start -0.7874 0.4064)
			(end -0.7874 -0.4064)
			(stroke
				(width 0.1524)
				(type default)
			)
			(layer "F.SilkS")
		)
		(fp_line
			(start -0.7874 -0.4064)
			(end 0.7874 -0.4064)
			(stroke
				(width 0.1524)
				(type default)
			)
			(layer "F.SilkS")
		)
		(fp_line
			(start 0.67945 0.3048)
			(end 0.120396 0.3048)
			(stroke
				(width 0.1)
				(type default)
			)
			(layer "F.Fab")
		)
		(fp_line
			(start 0.67945 -0.3048)
			(end 0.67945 0.3048)
			(stroke
				(width 0.1)
				(type default)
			)
			(layer "F.Fab")
		)
		(fp_line
			(start 0.12065 -0.2794)
			(end 0.12065 -0.3048)
			(stroke
				(width 0.1)
				(type default)
			)
			(layer "F.Fab")
		)
		(fp_line
			(start 0.12065 -0.3048)
			(end 0.67945 -0.3048)
			(stroke
				(width 0.1)
				(type default)
			)
			(layer "F.Fab")
		)
		(fp_line
			(start 0.120396 0.3048)
			(end 0.120396 0.2794)
			(stroke
				(width 0.1)
				(type default)
			)
			(layer "F.Fab")
		)
		(fp_line
			(start 0.120396 0.2794)
			(end -0.12065 0.2794)
			(stroke
				(width 0.1)
				(type default)
			)
			(layer "F.Fab")
		)
		(fp_line
			(start -0.12065 0.3048)
			(end -0.67945 0.3048)
			(stroke
				(width 0.1)
				(type default)
			)
			(layer "F.Fab")
		)
		(fp_line
			(start -0.12065 0.2794)
			(end -0.12065 0.3048)
			(stroke
				(width 0.1)
				(type default)
			)
			(layer "F.Fab")
		)
		(fp_line
			(start -0.12065 -0.2794)
			(end 0.12065 -0.2794)
			(stroke
				(width 0.1)
				(type default)
			)
			(layer "F.Fab")
		)
		(fp_line
			(start -0.12065 -0.305054)
			(end -0.12065 -0.2794)
			(stroke
				(width 0.1)
				(type default)
			)
			(layer "F.Fab")
		)
		(fp_line
			(start -0.67945 0.3048)
			(end -0.67945 -0.305054)
			(stroke
				(width 0.1)
				(type default)
			)
			(layer "F.Fab")
		)
		(fp_line
			(start -0.67945 -0.305054)
			(end -0.12065 -0.305054)
			(stroke
				(width 0.1)
				(type default)
			)
			(layer "F.Fab")
		)
		(pad "1" smd circle
			(at -0.40005 0 180)
			(size 0 0)
			(layers "F.Cu" "F.Mask" "F.Paste")
			(net "GND")
		)
		(pad "2" smd circle
			(at 0.40005 0 180)
			(size 0 0)
			(layers "F.Cu" "F.Mask" "F.Paste")
			(net "P1V8_PEX")
		)
	)
)
